(kicad_pcb
	(version 20260206)
	(generator "pcbnew")
	(generator_version "10.0")
	(general
		(thickness 1.6)
		(legacy_teardrops no)
	)
	(paper "A4")
	(title_block
		(title "fcb — 12433-1M.1206WZS1330.brd")
		(comment 1 "Open Vault / Knox (Wiwynn) / footprints 487-490 of 495")
	)
	(layers
		(0 "F.Cu" signal "TOP")
		(4 "In1.Cu" signal "L2GND")
		(6 "In2.Cu" signal "L3VCC")
		(2 "B.Cu" signal "BOTTOM")
		(9 "F.Adhes" user "F.Adhesive")
		(11 "B.Adhes" user "B.Adhesive")
		(13 "F.Paste" user "Package Geometry/Pastemask Top")
		(15 "B.Paste" user "Package Geometry/Pastemask Bottom")
		(5 "F.SilkS" user "Ref Des/Silkscreen Top")
		(7 "B.SilkS" user "Ref Des/Silkscreen Bottom")
		(1 "F.Mask" user "Board Geometry/Soldermask Top")
		(3 "B.Mask" user "Board Geometry/Soldermask Bottom")
		(17 "Dwgs.User" user "User.Drawings")
		(19 "Cmts.User" user "User.Comments")
		(21 "Eco1.User" user "User.Eco1")
		(23 "Eco2.User" user "User.Eco2")
		(25 "Edge.Cuts" user "Board Geometry/Outline")
		(27 "Margin" user)
		(31 "F.CrtYd" user "Package Geometry/Place Bound Top")
		(29 "B.CrtYd" user "Package Geometry/Place Bound Bottom")
		(35 "F.Fab" user "Ref Des/Assembly Top")
		(33 "B.Fab" user "Ref Des/Assembly Bottom")
	)
	(footprint ""
		(layer "F.Cu")
		(at 45.499782 -144.999964)
		(property "Reference" "H8"
			(at 0 0 0)
			(layer "F.SilkS")
			(hide yes)
			(effects
				(font
					(size 1.27 1.27)
				)
			)
		)
		(property "Value" "HOLE315R138"
			(at 0 -7.0612 0)
			(unlocked yes)
			(layer "F.Fab")
			(hide yes)
			(effects
				(font
					(size 1.016 1.016)
					(thickness 0.1524)
				)
			)
		)
		(property "Device Type" "HOLE315R138"
			(at 0 -8.5852 0)
			(unlocked yes)
			(layer "F.Fab")
			(hide yes)
			(effects
				(font
					(size 1.016 1.016)
					(thickness 0.1524)
				)
			)
		)
		(duplicate_pad_numbers_are_jumpers no)
		(fp_poly
			(pts
				(xy 0 4.3053) (xy -0.13462 4.30276) (xy -0.27051 4.29641) (xy -0.40513 4.28625) (xy -0.53975 4.27101)
				(xy -0.6731 4.25196) (xy -0.80645 4.2291) (xy -0.9398 4.20116) (xy -1.07061 4.17068) (xy -1.20142 4.13385)
				(xy -1.33096 4.09448) (xy -1.45796 4.0513) (xy -1.58496 4.00304) (xy -1.70942 3.95097) (xy -1.83261 3.89509)
				(xy -1.95453 3.83667) (xy -2.07391 3.77317) (xy -2.19202 3.70586) (xy -2.30632 3.63474) (xy -2.41935 3.56108)
				(xy -2.53111 3.48361) (xy -2.63906 3.40233) (xy -2.74447 3.31724) (xy -2.84734 3.22961) (xy -2.94767 3.13817)
				(xy -3.04419 3.04419) (xy -3.13817 2.94767) (xy -3.22961 2.84734) (xy -3.31724 2.74447) (xy -3.40233 2.63906)
				(xy -3.48361 2.53111) (xy -3.56108 2.41935) (xy -3.63474 2.30632) (xy -3.70586 2.19202) (xy -3.77317 2.07391)
				(xy -3.83667 1.95453) (xy -3.89509 1.83261) (xy -3.95097 1.70942) (xy -4.00304 1.58496) (xy -4.0513 1.45796)
				(xy -4.09448 1.33096) (xy -4.13385 1.20142) (xy -4.17068 1.07061) (xy -4.20116 0.9398) (xy -4.2291 0.80645)
				(xy -4.25196 0.6731) (xy -4.27101 0.53975) (xy -4.28625 0.40513) (xy -4.29641 0.27051) (xy -4.30276 0.13462)
				(xy -4.3053 0) (xy -4.30276 -0.13462) (xy -4.29641 -0.27051) (xy -4.28625 -0.40513) (xy -4.27101 -0.53975)
				(xy -4.25196 -0.6731) (xy -4.2291 -0.80645) (xy -4.20116 -0.9398) (xy -4.17068 -1.07061) (xy -4.13385 -1.20142)
				(xy -4.09448 -1.33096) (xy -4.0513 -1.45796) (xy -4.00304 -1.58496) (xy -3.95097 -1.70942) (xy -3.89509 -1.83261)
				(xy -3.83667 -1.95453) (xy -3.77317 -2.07391) (xy -3.70586 -2.19202) (xy -3.63474 -2.30632) (xy -3.56108 -2.41935)
				(xy -3.48361 -2.53111) (xy -3.40233 -2.63906) (xy -3.31724 -2.74447) (xy -3.22961 -2.84734) (xy -3.13817 -2.94767)
				(xy -3.04419 -3.04419) (xy -2.94767 -3.13817) (xy -2.84734 -3.22961) (xy -2.74447 -3.31724) (xy -2.63906 -3.40233)
				(xy -2.53111 -3.48361) (xy -2.41935 -3.56108) (xy -2.30632 -3.63474) (xy -2.19202 -3.70586) (xy -2.07391 -3.77317)
				(xy -1.95453 -3.83667) (xy -1.83261 -3.89509) (xy -1.70942 -3.95097) (xy -1.58496 -4.00304) (xy -1.45796 -4.0513)
				(xy -1.33096 -4.09448) (xy -1.20142 -4.13385) (xy -1.07061 -4.17068) (xy -0.9398 -4.20116) (xy -0.80645 -4.2291)
				(xy -0.6731 -4.25196) (xy -0.53975 -4.27101) (xy -0.40513 -4.28625) (xy -0.27051 -4.29641) (xy -0.13462 -4.30276)
				(xy 0 -4.3053) (xy 0.13462 -4.30276) (xy 0.27051 -4.29641) (xy 0.40513 -4.28625) (xy 0.53975 -4.27101)
				(xy 0.6731 -4.25196) (xy 0.80645 -4.2291) (xy 0.9398 -4.20116) (xy 1.07061 -4.17068) (xy 1.20142 -4.13385)
				(xy 1.33096 -4.09448) (xy 1.45796 -4.0513) (xy 1.58496 -4.00304) (xy 1.70942 -3.95097) (xy 1.83261 -3.89509)
				(xy 1.95453 -3.83667) (xy 2.07391 -3.77317) (xy 2.19202 -3.70586) (xy 2.30632 -3.63474) (xy 2.41935 -3.56108)
				(xy 2.53111 -3.48361) (xy 2.63906 -3.40233) (xy 2.74447 -3.31724) (xy 2.84734 -3.22961) (xy 2.94767 -3.13817)
				(xy 3.04419 -3.04419) (xy 3.13817 -2.94767) (xy 3.22961 -2.84734) (xy 3.31724 -2.74447) (xy 3.40233 -2.63906)
				(xy 3.48361 -2.53111) (xy 3.56108 -2.41935) (xy 3.63474 -2.30632) (xy 3.70586 -2.19202) (xy 3.77317 -2.07391)
				(xy 3.83667 -1.95453) (xy 3.89509 -1.83261) (xy 3.95097 -1.70942) (xy 4.00304 -1.58496) (xy 4.0513 -1.45796)
				(xy 4.09448 -1.33096) (xy 4.13385 -1.20142) (xy 4.17068 -1.07061) (xy 4.20116 -0.9398) (xy 4.2291 -0.80645)
				(xy 4.25196 -0.6731) (xy 4.27101 -0.53975) (xy 4.28625 -0.40513) (xy 4.29641 -0.27051) (xy 4.30276 -0.13462)
				(xy 4.3053 0) (xy 4.30276 0.13462) (xy 4.29641 0.27051) (xy 4.28625 0.40513) (xy 4.27101 0.53975)
				(xy 4.25196 0.6731) (xy 4.2291 0.80645) (xy 4.20116 0.9398) (xy 4.17068 1.07061) (xy 4.13385 1.20142)
				(xy 4.09448 1.33096) (xy 4.0513 1.45796) (xy 4.00304 1.58496) (xy 3.95097 1.70942) (xy 3.89509 1.83261)
				(xy 3.83667 1.95453) (xy 3.77317 2.07391) (xy 3.70586 2.19202) (xy 3.63474 2.30632) (xy 3.56108 2.41935)
				(xy 3.48361 2.53111) (xy 3.40233 2.63906) (xy 3.31724 2.74447) (xy 3.22961 2.84734) (xy 3.13817 2.94767)
				(xy 3.04419 3.04419) (xy 2.94767 3.13817) (xy 2.84734 3.22961) (xy 2.74447 3.31724) (xy 2.63906 3.40233)
				(xy 2.53111 3.48361) (xy 2.41935 3.56108) (xy 2.30632 3.63474) (xy 2.19202 3.70586) (xy 2.07391 3.77317)
				(xy 1.95453 3.83667) (xy 1.83261 3.89509) (xy 1.70942 3.95097) (xy 1.58496 4.00304) (xy 1.45796 4.0513)
				(xy 1.33096 4.09448) (xy 1.20142 4.13385) (xy 1.07061 4.17068) (xy 0.9398 4.20116) (xy 0.80645 4.2291)
				(xy 0.6731 4.25196) (xy 0.53975 4.27101) (xy 0.40513 4.28625) (xy 0.27051 4.29641) (xy 0.13462 4.30276)
			)
			(stroke
				(width 0)
				(type default)
			)
			(fill no)
			(layer "F.CrtYd")
		)
		(fp_poly
			(pts
				(xy 0 4.3053) (xy -0.13462 4.30276) (xy -0.27051 4.29641) (xy -0.40513 4.28625) (xy -0.53975 4.27101)
				(xy -0.6731 4.25196) (xy -0.80645 4.2291) (xy -0.9398 4.20116) (xy -1.07061 4.17068) (xy -1.20142 4.13385)
				(xy -1.33096 4.09448) (xy -1.45796 4.0513) (xy -1.58496 4.00304) (xy -1.70942 3.95097) (xy -1.83261 3.89509)
				(xy -1.95453 3.83667) (xy -2.07391 3.77317) (xy -2.19202 3.70586) (xy -2.30632 3.63474) (xy -2.41935 3.56108)
				(xy -2.53111 3.48361) (xy -2.63906 3.40233) (xy -2.74447 3.31724) (xy -2.84734 3.22961) (xy -2.94767 3.13817)
				(xy -3.04419 3.04419) (xy -3.13817 2.94767) (xy -3.22961 2.84734) (xy -3.31724 2.74447) (xy -3.40233 2.63906)
				(xy -3.48361 2.53111) (xy -3.56108 2.41935) (xy -3.63474 2.30632) (xy -3.70586 2.19202) (xy -3.77317 2.07391)
				(xy -3.83667 1.95453) (xy -3.89509 1.83261) (xy -3.95097 1.70942) (xy -4.00304 1.58496) (xy -4.0513 1.45796)
				(xy -4.09448 1.33096) (xy -4.13385 1.20142) (xy -4.17068 1.07061) (xy -4.20116 0.9398) (xy -4.2291 0.80645)
				(xy -4.25196 0.6731) (xy -4.27101 0.53975) (xy -4.28625 0.40513) (xy -4.29641 0.27051) (xy -4.30276 0.13462)
				(xy -4.3053 0) (xy -4.30276 -0.13462) (xy -4.29641 -0.27051) (xy -4.28625 -0.40513) (xy -4.27101 -0.53975)
				(xy -4.25196 -0.6731) (xy -4.2291 -0.80645) (xy -4.20116 -0.9398) (xy -4.17068 -1.07061) (xy -4.13385 -1.20142)
				(xy -4.09448 -1.33096) (xy -4.0513 -1.45796) (xy -4.00304 -1.58496) (xy -3.95097 -1.70942) (xy -3.89509 -1.83261)
				(xy -3.83667 -1.95453) (xy -3.77317 -2.07391) (xy -3.70586 -2.19202) (xy -3.63474 -2.30632) (xy -3.56108 -2.41935)
				(xy -3.48361 -2.53111) (xy -3.40233 -2.63906) (xy -3.31724 -2.74447) (xy -3.22961 -2.84734) (xy -3.13817 -2.94767)
				(xy -3.04419 -3.04419) (xy -2.94767 -3.13817) (xy -2.84734 -3.22961) (xy -2.74447 -3.31724) (xy -2.63906 -3.40233)
				(xy -2.53111 -3.48361) (xy -2.41935 -3.56108) (xy -2.30632 -3.63474) (xy -2.19202 -3.70586) (xy -2.07391 -3.77317)
				(xy -1.95453 -3.83667) (xy -1.83261 -3.89509) (xy -1.70942 -3.95097) (xy -1.58496 -4.00304) (xy -1.45796 -4.0513)
				(xy -1.33096 -4.09448) (xy -1.20142 -4.13385) (xy -1.07061 -4.17068) (xy -0.9398 -4.20116) (xy -0.80645 -4.2291)
				(xy -0.6731 -4.25196) (xy -0.53975 -4.27101) (xy -0.40513 -4.28625) (xy -0.27051 -4.29641) (xy -0.13462 -4.30276)
				(xy 0 -4.3053) (xy 0.13462 -4.30276) (xy 0.27051 -4.29641) (xy 0.40513 -4.28625) (xy 0.53975 -4.27101)
				(xy 0.6731 -4.25196) (xy 0.80645 -4.2291) (xy 0.9398 -4.20116) (xy 1.07061 -4.17068) (xy 1.20142 -4.13385)
				(xy 1.33096 -4.09448) (xy 1.45796 -4.0513) (xy 1.58496 -4.00304) (xy 1.70942 -3.95097) (xy 1.83261 -3.89509)
				(xy 1.95453 -3.83667) (xy 2.07391 -3.77317) (xy 2.19202 -3.70586) (xy 2.30632 -3.63474) (xy 2.41935 -3.56108)
				(xy 2.53111 -3.48361) (xy 2.63906 -3.40233) (xy 2.74447 -3.31724) (xy 2.84734 -3.22961) (xy 2.94767 -3.13817)
				(xy 3.04419 -3.04419) (xy 3.13817 -2.94767) (xy 3.22961 -2.84734) (xy 3.31724 -2.74447) (xy 3.40233 -2.63906)
				(xy 3.48361 -2.53111) (xy 3.56108 -2.41935) (xy 3.63474 -2.30632) (xy 3.70586 -2.19202) (xy 3.77317 -2.07391)
				(xy 3.83667 -1.95453) (xy 3.89509 -1.83261) (xy 3.95097 -1.70942) (xy 4.00304 -1.58496) (xy 4.0513 -1.45796)
				(xy 4.09448 -1.33096) (xy 4.13385 -1.20142) (xy 4.17068 -1.07061) (xy 4.20116 -0.9398) (xy 4.2291 -0.80645)
				(xy 4.25196 -0.6731) (xy 4.27101 -0.53975) (xy 4.28625 -0.40513) (xy 4.29641 -0.27051) (xy 4.30276 -0.13462)
				(xy 4.3053 0) (xy 4.30276 0.13462) (xy 4.29641 0.27051) (xy 4.28625 0.40513) (xy 4.27101 0.53975)
				(xy 4.25196 0.6731) (xy 4.2291 0.80645) (xy 4.20116 0.9398) (xy 4.17068 1.07061) (xy 4.13385 1.20142)
				(xy 4.09448 1.33096) (xy 4.0513 1.45796) (xy 4.00304 1.58496) (xy 3.95097 1.70942) (xy 3.89509 1.83261)
				(xy 3.83667 1.95453) (xy 3.77317 2.07391) (xy 3.70586 2.19202) (xy 3.63474 2.30632) (xy 3.56108 2.41935)
				(xy 3.48361 2.53111) (xy 3.40233 2.63906) (xy 3.31724 2.74447) (xy 3.22961 2.84734) (xy 3.13817 2.94767)
				(xy 3.04419 3.04419) (xy 2.94767 3.13817) (xy 2.84734 3.22961) (xy 2.74447 3.31724) (xy 2.63906 3.40233)
				(xy 2.53111 3.48361) (xy 2.41935 3.56108) (xy 2.30632 3.63474) (xy 2.19202 3.70586) (xy 2.07391 3.77317)
				(xy 1.95453 3.83667) (xy 1.83261 3.89509) (xy 1.70942 3.95097) (xy 1.58496 4.00304) (xy 1.45796 4.0513)
				(xy 1.33096 4.09448) (xy 1.20142 4.13385) (xy 1.07061 4.17068) (xy 0.9398 4.20116) (xy 0.80645 4.2291)
				(xy 0.6731 4.25196) (xy 0.53975 4.27101) (xy 0.40513 4.28625) (xy 0.27051 4.29641) (xy 0.13462 4.30276)
			)
			(stroke
				(width 0)
				(type default)
			)
			(fill no)
			(layer "F.Fab")
		)
		(pad "1" thru_hole circle
			(at 0 0)
			(size 8.001 8.001)
			(drill 3.5052)
			(layers "*.Cu" "*.Mask")
			(remove_unused_layers no)
			(net "GND")
			(clearance -1.7399)
			(thermal_gap 0.3048)
			(padstack
				(mode front_inner_back)
				(layer "Inner"
					(shape circle)
					(size 3.9116 3.9116)
					(clearance 0.3048)
				)
				(layer "B.Cu"
					(shape circle)
					(size 8.001 8.001)
					(clearance -1.7399)
				)
			)
		)
	)
	(footprint ""
		(layer "F.Cu")
		(at 24.8666 -136.6012 90)
		(property "Reference" "PC89"
			(at 0 0 90)
			(layer "F.SilkS")
			(hide yes)
			(effects
				(font
					(size 1.27 1.27)
				)
			)
		)
		(property "Value" "SCD1U25V2KX-GP"
			(at 1.1811 -2.7051 90)
			(unlocked yes)
			(layer "F.Fab")
			(hide yes)
			(effects
				(font
					(size 1.016 1.016)
					(thickness 0.1524)
				)
			)
		)
		(property "Device Type" "C402H22"
			(at 1.1811 -4.2291 90)
			(unlocked yes)
			(layer "F.Fab")
			(hide yes)
			(effects
				(font
					(size 1.016 1.016)
					(thickness 0.1524)
				)
			)
		)
		(duplicate_pad_numbers_are_jumpers no)
		(fp_rect
			(start -0.4318 0.9525)
			(end 0.4318 -0.9525)
			(stroke
				(width 0)
				(type default)
			)
			(fill no)
			(layer "F.CrtYd")
		)
		(fp_rect
			(start -0.4318 0.9525)
			(end 0.4318 -0.9525)
			(stroke
				(width 0)
				(type default)
			)
			(fill no)
			(layer "F.Fab")
		)
		(pad "1" smd custom
			(at 0 -0.4445 90)
			(size 0.1524 0.1524)
			(layers "F.Cu" "F.Mask" "F.Paste")
			(net "P12VU_2490_VCC")
			(options
				(clearance outline)
				(anchor circle)
			)
			(primitives
				(gr_poly
					(pts
						(arc
							(start 0.3048 -0.2032)
							(mid 0.275042 -0.275042)
							(end 0.2032 -0.3048)
						)
						(arc
							(start -0.2032 -0.3048)
							(mid -0.275042 -0.275042)
							(end -0.3048 -0.2032)
						)
						(arc
							(start -0.3048 0.2032)
							(mid -0.275042 0.275042)
							(end -0.2032 0.3048)
						)
						(arc
							(start 0.2032 0.3048)
							(mid 0.275042 0.275042)
							(end 0.3048 0.2032)
						)
					)
					(width 0)
					(fill yes)
				)
			)
		)
		(pad "2" smd custom
			(at 0 0.4445 90)
			(size 0.1524 0.1524)
			(layers "F.Cu" "F.Mask" "F.Paste")
			(net "GND")
			(options
				(clearance outline)
				(anchor circle)
			)
			(primitives
				(gr_poly
					(pts
						(arc
							(start 0.3048 -0.2032)
							(mid 0.275042 -0.275042)
							(end 0.2032 -0.3048)
						)
						(arc
							(start -0.2032 -0.3048)
							(mid -0.275042 -0.275042)
							(end -0.3048 -0.2032)
						)
						(arc
							(start -0.3048 0.2032)
							(mid -0.275042 0.275042)
							(end -0.2032 0.3048)
						)
						(arc
							(start 0.2032 0.3048)
							(mid 0.275042 0.275042)
							(end 0.3048 0.2032)
						)
					)
					(width 0)
					(fill yes)
				)
			)
		)
	)
	(footprint ""
		(layer "F.Cu")
		(at 45.83811 -160.825434)
		(property "Reference" "C6"
			(at 0 0 0)
			(layer "F.SilkS")
			(hide yes)
			(effects
				(font
					(size 1.27 1.27)
				)
			)
		)
		(property "Value" "SC4D7U6D3V2MX-GP-U"
			(at -1.524 -1.905 0)
			(unlocked yes)
			(layer "F.Fab")
			(hide yes)
			(effects
				(font
					(size 1.016 1.016)
					(thickness 0.1524)
				)
			)
		)
		(property "Device Type" "C402-TO0D2H26"
			(at -1.524 -3.429 0)
			(unlocked yes)
			(layer "F.Fab")
			(hide yes)
			(effects
				(font
					(size 1.016 1.016)
					(thickness 0.1524)
				)
			)
		)
		(duplicate_pad_numbers_are_jumpers no)
		(fp_rect
			(start -0.4826 0.889)
			(end 0.4826 -0.889)
			(stroke
				(width 0)
				(type default)
			)
			(fill no)
			(layer "F.CrtYd")
		)
		(fp_rect
			(start -0.4826 0.889)
			(end 0.4826 -0.889)
			(stroke
				(width 0)
				(type default)
			)
			(fill no)
			(layer "F.Fab")
		)
		(pad "1" smd custom
			(at 0 -0.4572)
			(size 0.1524 0.1524)
			(layers "F.Cu" "F.Mask" "F.Paste")
			(net "P3V3")
			(options
				(clearance outline)
				(anchor circle)
			)
			(primitives
				(gr_poly
					(pts
						(arc
							(start -0.254 0.3048)
							(mid -0.325842 0.275042)
							(end -0.3556 0.2032)
						)
						(arc
							(start -0.3556 -0.2032)
							(mid -0.325842 -0.275042)
							(end -0.254 -0.3048)
						)
						(arc
							(start 0.254 -0.3048)
							(mid 0.325842 -0.275042)
							(end 0.3556 -0.2032)
						)
						(arc
							(start 0.3556 0.2032)
							(mid 0.325842 0.275042)
							(end 0.254 0.3048)
						)
					)
					(width 0)
					(fill yes)
				)
			)
		)
		(pad "2" smd custom
			(at 0 0.4572)
			(size 0.1524 0.1524)
			(layers "F.Cu" "F.Mask" "F.Paste")
			(net "GND")
			(options
				(clearance outline)
				(anchor circle)
			)
			(primitives
				(gr_poly
					(pts
						(arc
							(start -0.254 0.3048)
							(mid -0.325842 0.275042)
							(end -0.3556 0.2032)
						)
						(arc
							(start -0.3556 -0.2032)
							(mid -0.325842 -0.275042)
							(end -0.254 -0.3048)
						)
						(arc
							(start 0.254 -0.3048)
							(mid 0.325842 -0.275042)
							(end 0.3556 -0.2032)
						)
						(arc
							(start 0.3556 0.2032)
							(mid 0.325842 0.275042)
							(end 0.254 0.3048)
						)
					)
					(width 0)
					(fill yes)
				)
			)
		)
	)
	(footprint ""
		(layer "F.Cu")
		(at 20.6756 -135.1788)
		(property "Reference" "PR95"
			(at 0 0 0)
			(layer "F.SilkS")
			(hide yes)
			(effects
				(font
					(size 1.27 1.27)
				)
			)
		)
		(property "Value" "0R2J-2-GP"
			(at 0.064008 -3.993896 0)
			(unlocked yes)
			(layer "F.Fab")
			(hide yes)
			(effects
				(font
					(size 1.016 1.016)
					(thickness 0.1524)
				)
			)
		)
		(property "Device Type" "R402H16"
			(at 0.064008 -5.517896 0)
			(unlocked yes)
			(layer "F.Fab")
			(hide yes)
			(effects
				(font
					(size 1.016 1.016)
					(thickness 0.1524)
				)
			)
		)
		(duplicate_pad_numbers_are_jumpers no)
		(fp_line
			(start -0.508 -0.9398)
			(end -0.508 0.9398)
			(stroke
				(width 0.1524)
				(type default)
			)
			(layer "F.SilkS")
		)
		(fp_line
			(start 0.508 -0.9398)
			(end -0.508 -0.9398)
			(stroke
				(width 0.1524)
				(type default)
			)
			(layer "F.SilkS")
		)
		(fp_rect
			(start -0.508 0.9398)
			(end 0.508 -0.9398)
			(stroke
				(width 0)
				(type default)
			)
			(fill no)
			(layer "F.CrtYd")
		)
		(fp_rect
			(start -0.508 0.9398)
			(end 0.508 -0.9398)
			(stroke
				(width 0)
				(type default)
			)
			(fill no)
			(layer "F.Fab")
		)
		(pad "1" smd custom
			(at 0 -0.4445)
			(size 0.1397 0.1397)
			(layers "F.Cu" "F.Mask" "F.Paste")
			(net "P12VU_2490_SENSE")
			(options
				(clearance outline)
				(anchor circle)
			)
			(primitives
				(gr_poly
					(pts
						(arc
							(start -0.1778 -0.2794)
							(mid -0.249642 -0.249642)
							(end -0.2794 -0.1778)
						)
						(arc
							(start -0.2794 0.1778)
							(mid -0.249642 0.249642)
							(end -0.1778 0.2794)
						)
						(arc
							(start 0.1778 0.2794)
							(mid 0.249642 0.249642)
							(end 0.2794 0.1778)
						)
						(arc
							(start 0.2794 -0.1778)
							(mid 0.249642 -0.249642)
							(end 0.1778 -0.2794)
						)
					)
					(width 0)
					(fill yes)
				)
			)
		)
		(pad "2" smd custom
			(at 0 0.4445)
			(size 0.1397 0.1397)
			(layers "F.Cu" "F.Mask" "F.Paste")
			(net "P12VU_NET")
			(options
				(clearance outline)
				(anchor circle)
			)
			(primitives
				(gr_poly
					(pts
						(arc
							(start -0.1778 -0.2794)
							(mid -0.249642 -0.249642)
							(end -0.2794 -0.1778)
						)
						(arc
							(start -0.2794 0.1778)
							(mid -0.249642 0.249642)
							(end -0.1778 0.2794)
						)
						(arc
							(start 0.1778 0.2794)
							(mid 0.249642 0.249642)
							(end 0.2794 0.1778)
						)
						(arc
							(start 0.2794 -0.1778)
							(mid 0.249642 -0.249642)
							(end 0.1778 -0.2794)
						)
					)
					(width 0)
					(fill yes)
				)
			)
		)
	)
)
